# S9S_MB_2U (Grand Teton) — schematic netlist excerpt (pin names and nets, part order shuffled) for the footprints in the layout excerpt that follows; sources: Cadence DE-HDL packaged netlist, KiCad conversion of 03242023_DA0F0TMBIJ0_F0T_Motherboard_J_brd_V01_OCP.brd

R744  Q_RES  75 1% CHIP  pkg 0402LF  page 133 : A = PVNN_TERM_CPU0 ; B = JTAG_CPU0_MUX_GTL_TDO
R108  Q_RES  33.2 1% CHIP  pkg 0402LF  page 241 : A = SMB_HOST_3V3AUX_SDA_R ; B = SMB_HOST_CLK_BUF_3V3AUX_SDA
C358  Q_CAP  47UF 4V 20% X6S  pkg C0805  page 75 : A = PVCCIN_CPU0 ; B = GND

(kicad_pcb
	(version 20260206)
	(generator "pcbnew")
	(generator_version "10.0")
	(general
		(thickness 1.6)
		(legacy_teardrops no)
	)
	(paper "A4")
	(title_block
		(title "03242023_DA0F0TMBIJ0_F0T_Motherboard_J_brd_V01_OCP.brd")
		(comment 1 "Grand Teton / footprints 5350-5352 of 6105")
	)
	(layers
		(0 "F.Cu" signal "TOP")
		(4 "In1.Cu" signal "GND")
		(6 "In2.Cu" signal "IN1")
		(8 "In3.Cu" signal "GND1")
		(10 "In4.Cu" signal "IN2")
		(12 "In5.Cu" signal "GND2")
		(14 "In6.Cu" signal "IN3")
		(16 "In7.Cu" signal "GND3")
		(18 "In8.Cu" signal "VCC")
		(20 "In9.Cu" signal "VCC1")
		(22 "In10.Cu" signal "GND4")
		(24 "In11.Cu" signal "IN4")
		(26 "In12.Cu" signal "GND5")
		(28 "In13.Cu" signal "IN5")
		(30 "In14.Cu" signal "GND6")
		(32 "In15.Cu" signal "IN6")
		(34 "In16.Cu" signal "GND7")
		(2 "B.Cu" signal "BOTTOM")
		(9 "F.Adhes" user "F.Adhesive")
		(11 "B.Adhes" user "B.Adhesive")
		(13 "F.Paste" user "Package Geometry/Pastemask Top")
		(15 "B.Paste" user "Package Geometry/Pastemask Bottom")
		(5 "F.SilkS" user "Ref Des/Silkscreen Top")
		(7 "B.SilkS" user "Ref Des/Silkscreen Bottom")
		(1 "F.Mask" user "Board Geometry/Soldermask Top")
		(3 "B.Mask" user "Board Geometry/Soldermask Bottom")
		(17 "Dwgs.User" user "User.Drawings")
		(19 "Cmts.User" user "User.Comments")
		(21 "Eco1.User" user "User.Eco1")
		(23 "Eco2.User" user "User.Eco2")
		(25 "Edge.Cuts" user "Board Geometry/Outline")
		(27 "Margin" user)
		(31 "F.CrtYd" user "Package Geometry/Place Bound Top")
		(29 "B.CrtYd" user "Package Geometry/Place Bound Bottom")
		(35 "F.Fab" user "Ref Des/Assembly Top")
		(33 "B.Fab" user "Ref Des/Assembly Bottom")
	)
	(footprint ""
		(layer "B.Cu")
		(at 366.120934 -255.853946 -90)
		(property "Reference" "C358"
			(at 0 0 90)
			(layer "B.SilkS")
			(hide yes)
			(effects
				(font
					(size 1.27 1.27)
				)
				(justify mirror)
			)
		)
		(property "Value" ""
			(at 0 0 90)
			(layer "B.Fab")
			(effects
				(font
					(size 1.27 1.27)
				)
				(justify mirror)
			)
		)
		(duplicate_pad_numbers_are_jumpers no)
		(fp_line
			(start -1.524 0.762)
			(end 1.524 0.762)
			(stroke
				(width 0.1524)
				(type default)
			)
			(layer "B.SilkS")
		)
		(fp_line
			(start 1.524 0.762)
			(end 1.524 -0.762)
			(stroke
				(width 0.1524)
				(type default)
			)
			(layer "B.SilkS")
		)
		(fp_line
			(start -1.524 -0.762)
			(end -1.524 0.762)
			(stroke
				(width 0.1524)
				(type default)
			)
			(layer "B.SilkS")
		)
		(fp_line
			(start 1.524 -0.762)
			(end -1.524 -0.762)
			(stroke
				(width 0.1524)
				(type default)
			)
			(layer "B.SilkS")
		)
		(fp_line
			(start -1.1049 0.724916)
			(end -1.1049 -0.724916)
			(stroke
				(width 0.1)
				(type default)
			)
			(layer "B.Fab")
		)
		(fp_line
			(start 1.1049 0.724916)
			(end -1.1049 0.724916)
			(stroke
				(width 0.1)
				(type default)
			)
			(layer "B.Fab")
		)
		(fp_line
			(start -1.1049 -0.724916)
			(end 1.1049 -0.724916)
			(stroke
				(width 0.1)
				(type default)
			)
			(layer "B.Fab")
		)
		(fp_line
			(start 1.1049 -0.724916)
			(end 1.1049 0.724916)
			(stroke
				(width 0.1)
				(type default)
			)
			(layer "B.Fab")
		)
		(pad "1" smd rect
			(at 0.889 0 270)
			(size 1.016 1.27)
			(layers "B.Cu" "B.Mask" "B.Paste")
			(net "PVCCIN_CPU0")
		)
		(pad "2" smd rect
			(at -0.889 0 270)
			(size 1.016 1.27)
			(layers "B.Cu" "B.Mask" "B.Paste")
			(net "GND")
		)
	)
	(footprint ""
		(layer "B.Cu")
		(at 327.613518 -188.61278 90)
		(property "Reference" "R744"
			(at 0 0 90)
			(layer "B.SilkS")
			(hide yes)
			(effects
				(font
					(size 1.27 1.27)
				)
				(justify mirror)
			)
		)
		(property "Value" ""
			(at 0 0 90)
			(layer "B.Fab")
			(effects
				(font
					(size 1.27 1.27)
				)
				(justify mirror)
			)
		)
		(duplicate_pad_numbers_are_jumpers no)
		(fp_line
			(start 0.7874 -0.4064)
			(end -0.7874 -0.4064)
			(stroke
				(width 0.1524)
				(type default)
			)
			(layer "B.SilkS")
		)
		(fp_line
			(start -0.7874 -0.4064)
			(end -0.7874 0.4064)
			(stroke
				(width 0.1524)
				(type default)
			)
			(layer "B.SilkS")
		)
		(fp_line
			(start 0.7874 0.4064)
			(end 0.7874 -0.4064)
			(stroke
				(width 0.1524)
				(type default)
			)
			(layer "B.SilkS")
		)
		(fp_line
			(start -0.7874 0.4064)
			(end 0.7874 0.4064)
			(stroke
				(width 0.1524)
				(type default)
			)
			(layer "B.SilkS")
		)
		(fp_line
			(start 0.67945 -0.305054)
			(end 0.12065 -0.305054)
			(stroke
				(width 0.1)
				(type default)
			)
			(layer "B.Fab")
		)
		(fp_line
			(start 0.12065 -0.305054)
			(end 0.12065 -0.2794)
			(stroke
				(width 0.1)
				(type default)
			)
			(layer "B.Fab")
		)
		(fp_line
			(start -0.12065 -0.3048)
			(end -0.67945 -0.3048)
			(stroke
				(width 0.1)
				(type default)
			)
			(layer "B.Fab")
		)
		(fp_line
			(start -0.67945 -0.3048)
			(end -0.67945 0.3048)
			(stroke
				(width 0.1)
				(type default)
			)
			(layer "B.Fab")
		)
		(fp_line
			(start 0.12065 -0.2794)
			(end -0.12065 -0.2794)
			(stroke
				(width 0.1)
				(type default)
			)
			(layer "B.Fab")
		)
		(fp_line
			(start -0.12065 -0.2794)
			(end -0.12065 -0.3048)
			(stroke
				(width 0.1)
				(type default)
			)
			(layer "B.Fab")
		)
		(fp_line
			(start 0.12065 0.2794)
			(end 0.12065 0.3048)
			(stroke
				(width 0.1)
				(type default)
			)
			(layer "B.Fab")
		)
		(fp_line
			(start -0.120396 0.2794)
			(end 0.12065 0.2794)
			(stroke
				(width 0.1)
				(type default)
			)
			(layer "B.Fab")
		)
		(fp_line
			(start 0.67945 0.3048)
			(end 0.67945 -0.305054)
			(stroke
				(width 0.1)
				(type default)
			)
			(layer "B.Fab")
		)
		(fp_line
			(start 0.12065 0.3048)
			(end 0.67945 0.3048)
			(stroke
				(width 0.1)
				(type default)
			)
			(layer "B.Fab")
		)
		(fp_line
			(start -0.120396 0.3048)
			(end -0.120396 0.2794)
			(stroke
				(width 0.1)
				(type default)
			)
			(layer "B.Fab")
		)
		(fp_line
			(start -0.67945 0.3048)
			(end -0.120396 0.3048)
			(stroke
				(width 0.1)
				(type default)
			)
			(layer "B.Fab")
		)
		(pad "1" smd circle
			(at 0.40005 0 270)
			(size 0 0)
			(layers "B.Cu" "B.Mask" "B.Paste")
			(net "PVNN_TERM_CPU0")
		)
		(pad "2" smd circle
			(at -0.40005 0 270)
			(size 0 0)
			(layers "B.Cu" "B.Mask" "B.Paste")
			(net "JTAG_CPU0_MUX_GTL_TDO")
		)
	)
	(footprint ""
		(layer "B.Cu")
		(at 239.615726 -128.670812 90)
		(property "Reference" "R108"
			(at 0 0 90)
			(layer "B.SilkS")
			(hide yes)
			(effects
				(font
					(size 1.27 1.27)
				)
				(justify mirror)
			)
		)
		(property "Value" ""
			(at 0 0 90)
			(layer "B.Fab")
			(effects
				(font
					(size 1.27 1.27)
				)
				(justify mirror)
			)
		)
		(duplicate_pad_numbers_are_jumpers no)
		(fp_line
			(start 0.7874 -0.4064)
			(end -0.7874 -0.4064)
			(stroke
				(width 0.1524)
				(type default)
			)
			(layer "B.SilkS")
		)
		(fp_line
			(start -0.7874 -0.4064)
			(end -0.7874 0.4064)
			(stroke
				(width 0.1524)
				(type default)
			)
			(layer "B.SilkS")
		)
		(fp_line
			(start 0.7874 0.4064)
			(end 0.7874 -0.4064)
			(stroke
				(width 0.1524)
				(type default)
			)
			(layer "B.SilkS")
		)
		(fp_line
			(start -0.7874 0.4064)
			(end 0.7874 0.4064)
			(stroke
				(width 0.1524)
				(type default)
			)
			(layer "B.SilkS")
		)
		(fp_line
			(start 0.67945 -0.305054)
			(end 0.12065 -0.305054)
			(stroke
				(width 0.1)
				(type default)
			)
			(layer "B.Fab")
		)
		(fp_line
			(start 0.12065 -0.305054)
			(end 0.12065 -0.2794)
			(stroke
				(width 0.1)
				(type default)
			)
			(layer "B.Fab")
		)
		(fp_line
			(start -0.12065 -0.3048)
			(end -0.67945 -0.3048)
			(stroke
				(width 0.1)
				(type default)
			)
			(layer "B.Fab")
		)
		(fp_line
			(start -0.67945 -0.3048)
			(end -0.67945 0.3048)
			(stroke
				(width 0.1)
				(type default)
			)
			(layer "B.Fab")
		)
		(fp_line
			(start 0.12065 -0.2794)
			(end -0.12065 -0.2794)
			(stroke
				(width 0.1)
				(type default)
			)
			(layer "B.Fab")
		)
		(fp_line
			(start -0.12065 -0.2794)
			(end -0.12065 -0.3048)
			(stroke
				(width 0.1)
				(type default)
			)
			(layer "B.Fab")
		)
		(fp_line
			(start 0.12065 0.2794)
			(end 0.12065 0.3048)
			(stroke
				(width 0.1)
				(type default)
			)
			(layer "B.Fab")
		)
		(fp_line
			(start -0.120396 0.2794)
			(end 0.12065 0.2794)
			(stroke
				(width 0.1)
				(type default)
			)
			(layer "B.Fab")
		)
		(fp_line
			(start 0.67945 0.3048)
			(end 0.67945 -0.305054)
			(stroke
				(width 0.1)
				(type default)
			)
			(layer "B.Fab")
		)
		(fp_line
			(start 0.12065 0.3048)
			(end 0.67945 0.3048)
			(stroke
				(width 0.1)
				(type default)
			)
			(layer "B.Fab")
		)
		(fp_line
			(start -0.120396 0.3048)
			(end -0.120396 0.2794)
			(stroke
				(width 0.1)
				(type default)
			)
			(layer "B.Fab")
		)
		(fp_line
			(start -0.67945 0.3048)
			(end -0.120396 0.3048)
			(stroke
				(width 0.1)
				(type default)
			)
			(layer "B.Fab")
		)
		(pad "1" smd circle
			(at 0.40005 0 270)
			(size 0 0)
			(layers "B.Cu" "B.Mask" "B.Paste")
			(net "SMB_HOST_3V3AUX_SDA_R")
		)
		(pad "2" smd circle
			(at -0.40005 0 270)
			(size 0 0)
			(layers "B.Cu" "B.Mask" "B.Paste")
			(net "SMB_HOST_CLK_BUF_3V3AUX_SDA")
		)
	)
)
